(kicad_pcb
	(version 20241229)
	(generator "pcbnew")
	(generator_version "9.0")
	(general
		(thickness 1.599998)
		(legacy_teardrops no)
	)
	(paper "A4")
	(title_block
		(title "Artix - Datacenter Secure Control Module (DC-SCM)")
		(date "2024-11-06")
		(rev "1.1.3")
		(comment 9 "footprint 110 of 544 (U14), pads 321-400 of 484")
	)
	(layers
		(0 "F.Cu" signal)
		(4 "In1.Cu" signal)
		(6 "In2.Cu" signal)
		(8 "In3.Cu" signal)
		(10 "In4.Cu" signal)
		(12 "In5.Cu" signal)
		(14 "In6.Cu" signal)
		(2 "B.Cu" signal)
		(9 "F.Adhes" user "F.Adhesive")
		(11 "B.Adhes" user "B.Adhesive")
		(13 "F.Paste" user)
		(15 "B.Paste" user)
		(5 "F.SilkS" user "F.Silkscreen")
		(7 "B.SilkS" user "B.Silkscreen")
		(1 "F.Mask" user)
		(3 "B.Mask" user)
		(17 "Dwgs.User" user "User.Drawings")
		(19 "Cmts.User" user "User.Comments")
		(21 "Eco1.User" user "User.Eco1")
		(23 "Eco2.User" user "User.Eco2")
		(25 "Edge.Cuts" user)
		(27 "Margin" user)
		(31 "F.CrtYd" user "F.Courtyard")
		(29 "B.CrtYd" user "B.Courtyard")
		(35 "F.Fab" user)
		(33 "B.Fab" user)
	)
	(footprint "antmicro-footprints:BGA-484_23x23mm_Layout22x22_P1mm_FGG484"
		(layer "F.Cu")
		(at 101.275 119.675 90)
		(property "Reference" "U14"
			(at 11.965 9.405 180)
			(layer "F.SilkS")
			(effects
				(font
					(size 0.7 0.7)
					(thickness 0.15)
				)
				(justify left bottom)
			)
		)
		(property "Value" "XC7A100T-FGG484"
			(at 0 13.1 90)
			(layer "F.Fab")
			(effects
				(font
					(size 0.7 0.7)
					(thickness 0.15)
				)
				(justify left bottom)
			)
		)
		(property "Datasheet" "https://docs.xilinx.com/v/u/en-US/ds181_Artix_7_Data_Sheet"
			(at 0 0 90)
			(layer "F.Fab")
			(hide yes)
			(effects
				(font
					(size 1.27 1.27)
					(thickness 0.15)
				)
			)
		)
		(property "Description" "Artix-7 Field Programmable Gate Array IC 210 324-LFBGA, CSPBGA"
			(at 0 0 90)
			(layer "F.Fab")
			(hide yes)
			(effects
				(font
					(size 1.27 1.27)
					(thickness 0.15)
				)
			)
		)
		(property "Author" "Antmicro"
			(at 220.95 18.4 0)
			(layer "F.Fab")
			(hide yes)
			(effects
				(font
					(size 1 1)
					(thickness 0.15)
				)
			)
		)
		(property "License" "Apache-2.0"
			(at 220.95 18.4 0)
			(layer "F.Fab")
			(hide yes)
			(effects
				(font
					(size 1 1)
					(thickness 0.15)
				)
			)
		)
		(property "MPN" "XC7A100T-FGG484"
			(at 220.95 18.4 0)
			(layer "F.Fab")
			(hide yes)
			(effects
				(font
					(size 1 1)
					(thickness 0.15)
				)
			)
		)
		(property "Manufacturer" "AMD-Xilinx"
			(at 220.95 18.4 0)
			(layer "F.Fab")
			(hide yes)
			(effects
				(font
					(size 1 1)
					(thickness 0.15)
				)
			)
		)
		(sheetname "/FPGA power supply/")
		(sheetfile "fpga-power-supply.kicad_sch")
		(solder_mask_margin 0.05)
		(attr smd)
		(pad "N13" smd circle
			(at 1.499 1.499 90)
			(size 0.5 0.5)
			(layers "F.Cu" "F.Mask" "F.Paste")
			(net 18 "I2C[5]_SCL")
			(pinfunction "IO_L23P_T3_A03_D19_14")
			(pintype "bidirectional")
		)
		(pad "N14" smd circle
			(at 2.499 1.499 90)
			(size 0.5 0.5)
			(layers "F.Cu" "F.Mask" "F.Paste")
			(net 17 "I2C[5]_SDA")
			(pinfunction "IO_L23N_T3_A02_D18_14")
			(pintype "bidirectional")
		)
		(pad "N15" smd circle
			(at 3.499 1.499 90)
			(size 0.5 0.5)
			(layers "F.Cu" "F.Mask" "F.Paste")
			(net 614 "unconnected-(U14A-IO_25_14-PadN15)")
			(pinfunction "IO_25_14")
			(pintype "bidirectional+no_connect")
		)
		(pad "N16" smd circle
			(at 4.498 1.499 90)
			(size 0.5 0.5)
			(layers "F.Cu" "F.Mask" "F.Paste")
			(net 1 "GND")
			(pinfunction "GND")
			(pintype "passive")
		)
		(pad "N17" smd circle
			(at 5.499 1.499 90)
			(size 0.5 0.5)
			(layers "F.Cu" "F.Mask" "F.Paste")
			(net 615 "unconnected-(U14A-IO_L21P_T3_DQS_14-PadN17)")
			(pinfunction "IO_L21P_T3_DQS_14")
			(pintype "bidirectional+no_connect")
		)
		(pad "N18" smd circle
			(at 6.499 1.499 90)
			(size 0.5 0.5)
			(layers "F.Cu" "F.Mask" "F.Paste")
			(net 414 "ETH_~{RESET}")
			(pinfunction "IO_L17P_T2_A26_15")
			(pintype "bidirectional")
		)
		(pad "N19" smd circle
			(at 7.499 1.499 90)
			(size 0.5 0.5)
			(layers "F.Cu" "F.Mask" "F.Paste")
			(net 616 "unconnected-(U14B-IO_L17N_T2_A25_15-PadN19)")
			(pinfunction "IO_L17N_T2_A25_15")
			(pintype "bidirectional+no_connect")
		)
		(pad "N20" smd circle
			(at 8.499 1.499 90)
			(size 0.5 0.5)
			(layers "F.Cu" "F.Mask" "F.Paste")
			(net 420 "ETH_INT_N")
			(pinfunction "IO_L18P_T2_A24_15")
			(pintype "bidirectional")
		)
		(pad "N21" smd circle
			(at 9.499 1.499 90)
			(size 0.5 0.5)
			(layers "F.Cu" "F.Mask" "F.Paste")
			(net 2 "VCC3V3")
			(pinfunction "VCCO_15")
			(pintype "passive")
		)
		(pad "N22" smd circle
			(at 10.499 1.499 90)
			(size 0.5 0.5)
			(layers "F.Cu" "F.Mask" "F.Paste")
			(net 141 "ETH_MDC")
			(pinfunction "IO_L15P_T2_DQS_15")
			(pintype "bidirectional")
		)
		(pad "P1" smd circle
			(at -10.5 2.499 90)
			(size 0.5 0.5)
			(layers "F.Cu" "F.Mask" "F.Paste")
			(net 167 "DDR3_A5")
			(pinfunction "IO_L20N_T3_35")
			(pintype "bidirectional")
		)
		(pad "P2" smd circle
			(at -9.5 2.499 90)
			(size 0.5 0.5)
			(layers "F.Cu" "F.Mask" "F.Paste")
			(net 151 "DDR3_A13")
			(pinfunction "IO_L22P_T3_35")
			(pintype "bidirectional")
		)
		(pad "P3" smd circle
			(at -8.5 2.499 90)
			(size 0.5 0.5)
			(layers "F.Cu" "F.Mask" "F.Paste")
			(net 1 "GND")
			(pinfunction "GND")
			(pintype "passive")
		)
		(pad "P4" smd circle
			(at -7.5 2.499 90)
			(size 0.5 0.5)
			(layers "F.Cu" "F.Mask" "F.Paste")
			(net 478 "DDR3_CLK_N")
			(pinfunction "IO_L21N_T3_DQS_35")
			(pintype "bidirectional")
		)
		(pad "P5" smd circle
			(at -6.5 2.499 90)
			(size 0.5 0.5)
			(layers "F.Cu" "F.Mask" "F.Paste")
			(net 479 "DDR3_CLK_P")
			(pinfunction "IO_L21P_T3_DQS_35")
			(pintype "bidirectional")
		)
		(pad "P6" smd circle
			(at -5.5 2.499 90)
			(size 0.5 0.5)
			(layers "F.Cu" "F.Mask" "F.Paste")
			(net 144 "DDR3_A14")
			(pinfunction "IO_L24P_T3_35")
			(pintype "bidirectional")
		)
		(pad "P7" smd circle
			(at -4.5 2.499 90)
			(size 0.5 0.5)
			(layers "F.Cu" "F.Mask" "F.Paste")
			(net 1 "GND")
			(pinfunction "GND")
			(pintype "passive")
		)
		(pad "P8" smd circle
			(at -3.5 2.499 90)
			(size 0.5 0.5)
			(layers "F.Cu" "F.Mask" "F.Paste")
			(net 6 "VCC1V0")
			(pinfunction "VCCINT")
			(pintype "passive")
		)
		(pad "P9" smd circle
			(at -2.5 2.499 90)
			(size 0.5 0.5)
			(layers "F.Cu" "F.Mask" "F.Paste")
			(net 1 "GND")
			(pinfunction "GND")
			(pintype "passive")
		)
		(pad "P10" smd circle
			(at -1.5 2.499 90)
			(size 0.5 0.5)
			(layers "F.Cu" "F.Mask" "F.Paste")
			(net 6 "VCC1V0")
			(pinfunction "VCCINT")
			(pintype "passive")
		)
		(pad "P11" smd circle
			(at -0.5 2.499 90)
			(size 0.5 0.5)
			(layers "F.Cu" "F.Mask" "F.Paste")
			(net 1 "GND")
			(pinfunction "GND")
			(pintype "passive")
		)
		(pad "P12" smd circle
			(at 0.498 2.499 90)
			(size 0.5 0.5)
			(layers "F.Cu" "F.Mask" "F.Paste")
			(net 5 "VCC1V8")
			(pinfunction "VCCAUX")
			(pintype "passive")
		)
		(pad "P13" smd circle
			(at 1.499 2.499 90)
			(size 0.5 0.5)
			(layers "F.Cu" "F.Mask" "F.Paste")
			(net 1 "GND")
			(pinfunction "GND")
			(pintype "passive")
		)
		(pad "P14" smd circle
			(at 2.499 2.499 90)
			(size 0.5 0.5)
			(layers "F.Cu" "F.Mask" "F.Paste")
			(net 617 "unconnected-(U14A-IO_L19P_T3_A10_D26_14-PadP14)")
			(pinfunction "IO_L19P_T3_A10_D26_14")
			(pintype "bidirectional+no_connect")
		)
		(pad "P15" smd circle
			(at 3.499 2.499 90)
			(size 0.5 0.5)
			(layers "F.Cu" "F.Mask" "F.Paste")
			(net 618 "unconnected-(U14A-IO_L22P_T3_A05_D21_14-PadP15)")
			(pinfunction "IO_L22P_T3_A05_D21_14")
			(pintype "bidirectional+no_connect")
		)
		(pad "P16" smd circle
			(at 4.498 2.499 90)
			(size 0.5 0.5)
			(layers "F.Cu" "F.Mask" "F.Paste")
			(net 586 "HPM_STBY_RDY_R")
			(pinfunction "IO_L24P_T3_A01_D17_14")
			(pintype "bidirectional")
		)
		(pad "P17" smd circle
			(at 5.499 2.499 90)
			(size 0.5 0.5)
			(layers "F.Cu" "F.Mask" "F.Paste")
			(net 321 "MMC_DAT0")
			(pinfunction "IO_L21N_T3_DQS_A06_D22_14")
			(pintype "bidirectional")
		)
		(pad "P18" smd circle
			(at 6.499 2.499 90)
			(size 0.5 0.5)
			(layers "F.Cu" "F.Mask" "F.Paste")
			(net 2 "VCC3V3")
			(pinfunction "VCCO_14")
			(pintype "passive")
		)
		(pad "P19" smd circle
			(at 7.499 2.499 90)
			(size 0.5 0.5)
			(layers "F.Cu" "F.Mask" "F.Paste")
			(net 624 "DBG_UART_RX")
			(pinfunction "IO_L5P_T0_D06_14")
			(pintype "bidirectional")
		)
		(pad "P20" smd circle
			(at 8.499 2.499 90)
			(size 0.5 0.5)
			(layers "F.Cu" "F.Mask" "F.Paste")
			(net 619 "unconnected-(U14A-IO_0_14-PadP20)")
			(pinfunction "IO_0_14")
			(pintype "bidirectional+no_connect")
		)
		(pad "P21" smd circle
			(at 9.499 2.499 90)
			(size 0.5 0.5)
			(layers "F.Cu" "F.Mask" "F.Paste")
			(net 332 "ROT_QSPI_DQ2")
			(pinfunction "IO_L2P_T0_D02_14")
			(pintype "bidirectional")
		)
		(pad "P22" smd circle
			(at 10.499 2.499 90)
			(size 0.5 0.5)
			(layers "F.Cu" "F.Mask" "F.Paste")
			(net 335 "ROT_QSPI_DQ0")
			(pinfunction "IO_L1P_T0_D00_MOSI_14")
			(pintype "bidirectional")
		)
		(pad "R1" smd circle
			(at -10.5 3.499 90)
			(size 0.5 0.5)
			(layers "F.Cu" "F.Mask" "F.Paste")
			(net 149 "DDR3_A9")
			(pinfunction "IO_L20P_T3_35")
			(pintype "bidirectional")
		)
		(pad "R2" smd circle
			(at -9.5 3.499 90)
			(size 0.5 0.5)
			(layers "F.Cu" "F.Mask" "F.Paste")
			(net 98 "QSPI1_CS0_N")
			(pinfunction "IO_L3N_T0_DQS_34")
			(pintype "bidirectional")
		)
		(pad "R3" smd circle
			(at -8.5 3.499 90)
			(size 0.5 0.5)
			(layers "F.Cu" "F.Mask" "F.Paste")
			(net 99 "QSPI1_D0")
			(pinfunction "IO_L3P_T0_DQS_34")
			(pintype "bidirectional")
		)
		(pad "R4" smd circle
			(at -7.5 3.499 90)
			(size 0.5 0.5)
			(layers "F.Cu" "F.Mask" "F.Paste")
			(net 97 "QSPI1_CLK")
			(pinfunction "IO_L13P_T2_MRCC_34")
			(pintype "bidirectional")
		)
		(pad "R5" smd circle
			(at -6.5 3.499 90)
			(size 0.5 0.5)
			(layers "F.Cu" "F.Mask" "F.Paste")
			(net 2 "VCC3V3")
			(pinfunction "VCCO_34")
			(pintype "passive")
		)
		(pad "R6" smd circle
			(at -5.5 3.499 90)
			(size 0.5 0.5)
			(layers "F.Cu" "F.Mask" "F.Paste")
			(net 620 "unconnected-(U14C-IO_L17P_T2_34-PadR6)")
			(pinfunction "IO_L17P_T2_34")
			(pintype "bidirectional+no_connect")
		)
		(pad "R7" smd circle
			(at -4.5 3.499 90)
			(size 0.5 0.5)
			(layers "F.Cu" "F.Mask" "F.Paste")
			(net 6 "VCC1V0")
			(pinfunction "VCCINT")
			(pintype "passive")
		)
		(pad "R8" smd circle
			(at -3.5 3.499 90)
			(size 0.5 0.5)
			(layers "F.Cu" "F.Mask" "F.Paste")
			(net 1 "GND")
			(pinfunction "GND")
			(pintype "passive")
		)
		(pad "R9" smd circle
			(at -2.5 3.499 90)
			(size 0.5 0.5)
			(layers "F.Cu" "F.Mask" "F.Paste")
			(net 6 "VCC1V0")
			(pinfunction "VCCINT")
			(pintype "passive")
		)
		(pad "R10" smd circle
			(at -1.5 3.499 90)
			(size 0.5 0.5)
			(layers "F.Cu" "F.Mask" "F.Paste")
			(net 1 "GND")
			(pinfunction "GND")
			(pintype "passive")
		)
		(pad "R11" smd circle
			(at -0.5 3.499 90)
			(size 0.5 0.5)
			(layers "F.Cu" "F.Mask" "F.Paste")
			(net 5 "VCC1V8")
			(pinfunction "VCCAUX")
			(pintype "passive")
		)
		(pad "R12" smd circle
			(at 0.498 3.499 90)
			(size 0.5 0.5)
			(layers "F.Cu" "F.Mask" "F.Paste")
			(net 1 "GND")
			(pinfunction "GND")
			(pintype "passive")
		)
		(pad "R13" smd circle
			(at 1.499 3.499 90)
			(size 0.5 0.5)
			(layers "F.Cu" "F.Mask" "F.Paste")
			(net 13 "JTAG_TDI")
			(pinfunction "TDI_0")
			(pintype "bidirectional")
		)
		(pad "R14" smd circle
			(at 2.499 3.499 90)
			(size 0.5 0.5)
			(layers "F.Cu" "F.Mask" "F.Paste")
			(net 621 "unconnected-(U14A-IO_L19N_T3_A09_D25_VREF_14-PadR14)")
			(pinfunction "IO_L19N_T3_A09_D25_VREF_14")
			(pintype "bidirectional+no_connect")
		)
		(pad "R15" smd circle
			(at 3.499 3.499 90)
			(size 0.5 0.5)
			(layers "F.Cu" "F.Mask" "F.Paste")
			(net 2 "VCC3V3")
			(pinfunction "VCCO_14")
			(pintype "passive")
		)
		(pad "R16" smd circle
			(at 4.498 3.499 90)
			(size 0.5 0.5)
			(layers "F.Cu" "F.Mask" "F.Paste")
			(net 622 "unconnected-(U14A-IO_L22N_T3_A04_D20_14-PadR16)")
			(pinfunction "IO_L22N_T3_A04_D20_14")
			(pintype "bidirectional+no_connect")
		)
		(pad "R17" smd circle
			(at 5.499 3.499 90)
			(size 0.5 0.5)
			(layers "F.Cu" "F.Mask" "F.Paste")
			(net 328 "MMC_DAT7")
			(pinfunction "IO_L24N_T3_A00_D16_14")
			(pintype "bidirectional")
		)
		(pad "R18" smd circle
			(at 6.499 3.499 90)
			(size 0.5 0.5)
			(layers "F.Cu" "F.Mask" "F.Paste")
			(net 323 "MMC_DAT2")
			(pinfunction "IO_L20P_T3_A08_D24_14")
			(pintype "bidirectional")
		)
		(pad "R19" smd circle
			(at 7.499 3.499 90)
			(size 0.5 0.5)
			(layers "F.Cu" "F.Mask" "F.Paste")
			(net 626 "DBG_UART_TX")
			(pinfunction "IO_L5N_T0_D07_14")
			(pintype "bidirectional")
		)
		(pad "R20" smd circle
			(at 8.499 3.499 90)
			(size 0.5 0.5)
			(layers "F.Cu" "F.Mask" "F.Paste")
			(net 1 "GND")
			(pinfunction "GND")
			(pintype "passive")
		)
		(pad "R21" smd circle
			(at 9.499 3.499 90)
			(size 0.5 0.5)
			(layers "F.Cu" "F.Mask" "F.Paste")
			(net 333 "ROT_QSPI_DQ3")
			(pinfunction "IO_L2N_T0_D03_14")
			(pintype "bidirectional")
		)
		(pad "R22" smd circle
			(at 10.499 3.499 90)
			(size 0.5 0.5)
			(layers "F.Cu" "F.Mask" "F.Paste")
			(net 336 "ROT_QSPI_DQ1")
			(pinfunction "IO_L1N_T0_D01_DIN_14")
			(pintype "bidirectional")
		)
		(pad "T1" smd circle
			(at -10.5 4.498 90)
			(size 0.5 0.5)
			(layers "F.Cu" "F.Mask" "F.Paste")
			(net 102 "QSPI1_D3")
			(pinfunction "IO_L1P_T0_34")
			(pintype "bidirectional")
		)
		(pad "T2" smd circle
			(at -9.5 4.498 90)
			(size 0.5 0.5)
			(layers "F.Cu" "F.Mask" "F.Paste")
			(net 2 "VCC3V3")
			(pinfunction "VCCO_34")
			(pintype "passive")
		)
		(pad "T3" smd circle
			(at -8.5 4.498 90)
			(size 0.5 0.5)
			(layers "F.Cu" "F.Mask" "F.Paste")
			(net 101 "QSPI1_D2")
			(pinfunction "IO_0_34")
			(pintype "bidirectional")
		)
		(pad "T4" smd circle
			(at -7.5 4.498 90)
			(size 0.5 0.5)
			(layers "F.Cu" "F.Mask" "F.Paste")
			(net 100 "QSPI1_D1")
			(pinfunction "IO_L13N_T2_MRCC_34")
			(pintype "bidirectional")
		)
		(pad "T5" smd circle
			(at -6.5 4.498 90)
			(size 0.5 0.5)
			(layers "F.Cu" "F.Mask" "F.Paste")
			(net 37 "I2C[9]_SCL")
			(pinfunction "IO_L14P_T2_SRCC_34")
			(pintype "bidirectional")
		)
		(pad "T6" smd circle
			(at -5.5 4.498 90)
			(size 0.5 0.5)
			(layers "F.Cu" "F.Mask" "F.Paste")
			(net 38 "I2C[9]_SDA")
			(pinfunction "IO_L17N_T2_34")
			(pintype "bidirectional")
		)
		(pad "T7" smd circle
			(at -4.5 4.498 90)
			(size 0.5 0.5)
			(layers "F.Cu" "F.Mask" "F.Paste")
			(net 1 "GND")
			(pinfunction "GND")
			(pintype "passive")
		)
		(pad "T8" smd circle
			(at -3.5 4.498 90)
			(size 0.5 0.5)
			(layers "F.Cu" "F.Mask" "F.Paste")
			(net 6 "VCC1V0")
			(pinfunction "VCCINT")
			(pintype "passive")
		)
		(pad "T9" smd circle
			(at -2.5 4.498 90)
			(size 0.5 0.5)
			(layers "F.Cu" "F.Mask" "F.Paste")
			(net 1 "GND")
			(pinfunction "GND")
			(pintype "passive")
		)
		(pad "T10" smd circle
			(at -1.5 4.498 90)
			(size 0.5 0.5)
			(layers "F.Cu" "F.Mask" "F.Paste")
			(net 6 "VCC1V0")
			(pinfunction "VCCINT")
			(pintype "passive")
		)
		(pad "T11" smd circle
			(at -0.5 4.498 90)
			(size 0.5 0.5)
			(layers "F.Cu" "F.Mask" "F.Paste")
			(net 1 "GND")
			(pinfunction "GND")
			(pintype "passive")
		)
		(pad "T12" smd circle
			(at 0.498 4.498 90)
			(size 0.5 0.5)
			(layers "F.Cu" "F.Mask" "F.Paste")
			(net 2 "VCC3V3")
			(pinfunction "VCCO_0")
			(pintype "passive")
		)
		(pad "T13" smd circle
			(at 1.499 4.498 90)
			(size 0.5 0.5)
			(layers "F.Cu" "F.Mask" "F.Paste")
			(net 16 "JTAG_TMS")
			(pinfunction "TMS_0")
			(pintype "bidirectional")
		)
		(pad "T14" smd circle
			(at 2.499 4.498 90)
			(size 0.5 0.5)
			(layers "F.Cu" "F.Mask" "F.Paste")
			(net 623 "unconnected-(U14A-IO_L15P_T2_DQS_13-PadT14)")
			(pinfunction "IO_L15P_T2_DQS_13")
			(pintype "bidirectional+no_connect")
		)
		(pad "T15" smd circle
			(at 3.499 4.498 90)
			(size 0.5 0.5)
			(layers "F.Cu" "F.Mask" "F.Paste")
			(net 625 "unconnected-(U14A-IO_L15N_T2_DQS_13-PadT15)")
			(pinfunction "IO_L15N_T2_DQS_13")
			(pintype "bidirectional+no_connect")
		)
		(pad "T16" smd circle
			(at 4.498 4.498 90)
			(size 0.5 0.5)
			(layers "F.Cu" "F.Mask" "F.Paste")
			(net 627 "unconnected-(U14A-IO_L17P_T2_13-PadT16)")
			(pinfunction "IO_L17P_T2_13")
			(pintype "bidirectional+no_connect")
		)
		(pad "T17" smd circle
			(at 5.499 4.498 90)
			(size 0.5 0.5)
			(layers "F.Cu" "F.Mask" "F.Paste")
			(net 1 "GND")
			(pinfunction "GND")
			(pintype "passive")
		)
		(pad "T18" smd circle
			(at 6.499 4.498 90)
			(size 0.5 0.5)
			(layers "F.Cu" "F.Mask" "F.Paste")
			(net 327 "MMC_DAT6")
			(pinfunction "IO_L20N_T3_A07_D23_14")
			(pintype "bidirectional")
		)
		(pad "T19" smd circle
			(at 7.499 4.498 90)
			(size 0.5 0.5)
			(layers "F.Cu" "F.Mask" "F.Paste")
			(net 344 "Net-(U14A-IO_L6P_T0_FCS_B_14)")
			(pinfunction "IO_L6P_T0_FCS_B_14")
			(pintype "bidirectional")
		)
		(pad "T20" smd circle
			(at 8.499 4.498 90)
			(size 0.5 0.5)
			(layers "F.Cu" "F.Mask" "F.Paste")
			(net 316 "USR_LED0")
			(pinfunction "IO_L6N_T0_D08_VREF_14")
			(pintype "bidirectional")
		)
		(pad "T21" smd circle
			(at 9.499 4.498 90)
			(size 0.5 0.5)
			(layers "F.Cu" "F.Mask" "F.Paste")
			(net 33 "UART1_SCM_RX")
			(pinfunction "IO_L4P_T0_D04_14")
			(pintype "bidirectional")
		)
		(pad "T22" smd circle
			(at 10.499 4.498 90)
			(size 0.5 0.5)
			(layers "F.Cu" "F.Mask" "F.Paste")
			(net 2 "VCC3V3")
			(pinfunction "VCCO_14")
			(pintype "passive")
		)
		(pad "U1" smd circle
			(at -10.5 5.499 90)
			(size 0.5 0.5)
			(layers "F.Cu" "F.Mask" "F.Paste")
			(net 388 "HPM_STBY_RST_N_R")
			(pinfunction "IO_L1N_T0_34")
			(pintype "bidirectional")
		)
		(pad "U2" smd circle
			(at -9.5 5.499 90)
			(size 0.5 0.5)
			(layers "F.Cu" "F.Mask" "F.Paste")
			(net 389 "SYS_PWRBTN_N_R")
			(pinfunction "IO_L2P_T0_34")
			(pintype "bidirectional")
		)
		(pad "U3" smd circle
			(at -8.5 5.499 90)
			(size 0.5 0.5)
			(layers "F.Cu" "F.Mask" "F.Paste")
			(net 387 "HPM_FW_RECOVERY_R")
			(pinfunction "IO_L6P_T0_34")
			(pintype "bidirectional")
		)
		(pad "U4" smd circle
			(at -7.5 5.499 90)
			(size 0.5 0.5)
			(layers "F.Cu" "F.Mask" "F.Paste")
			(net 1 "GND")
			(pinfunction "GND")
			(pintype "passive")
		)
	)
)
